(kicad_pcb
	(version 20260206)
	(generator "pcbnew")
	(generator_version "10.0")
	(general
		(thickness 1.6)
		(legacy_teardrops no)
	)
	(paper "A4")
	(title_block
		(title "Bryce Canyon_IOM_M2_16342-2_OCP.brd")
		(comment 1 "Bryce Canyon / footprints 637-643 of 1146")
	)
	(layers
		(0 "F.Cu" signal "TOP")
		(4 "In1.Cu" signal "L2GND")
		(6 "In2.Cu" signal "L3")
		(8 "In3.Cu" signal "L4VCC")
		(10 "In4.Cu" signal "L5VCC")
		(12 "In5.Cu" signal "L6")
		(14 "In6.Cu" signal "L7GND")
		(2 "B.Cu" signal "BOTTOM")
		(9 "F.Adhes" user "F.Adhesive")
		(11 "B.Adhes" user "B.Adhesive")
		(13 "F.Paste" user "Package Geometry/Pastemask Top")
		(15 "B.Paste" user "Package Geometry/Pastemask Bottom")
		(5 "F.SilkS" user "Ref Des/Silkscreen Top")
		(7 "B.SilkS" user "Ref Des/Silkscreen Bottom")
		(1 "F.Mask" user "Board Geometry/Soldermask Top")
		(3 "B.Mask" user "Board Geometry/Soldermask Bottom")
		(17 "Dwgs.User" user "User.Drawings")
		(19 "Cmts.User" user "User.Comments")
		(21 "Eco1.User" user "User.Eco1")
		(23 "Eco2.User" user "User.Eco2")
		(25 "Edge.Cuts" user "Board Geometry/Outline")
		(27 "Margin" user)
		(31 "F.CrtYd" user "Package Geometry/Place Bound Top")
		(29 "B.CrtYd" user "Package Geometry/Place Bound Bottom")
		(35 "F.Fab" user "Ref Des/Assembly Top")
		(33 "B.Fab" user "Ref Des/Assembly Bottom")
	)
	(footprint ""
		(layer "F.Cu")
		(at 125.203712 -15.532354 -90)
		(property "Reference" "PQ1"
			(at 0 0 270)
			(layer "F.SilkS")
			(hide yes)
			(effects
				(font
					(size 1.27 1.27)
				)
			)
		)
		(property "Value" "MMBT3904-3-GP"
			(at 0.10287 -10.29843 270)
			(unlocked yes)
			(layer "F.Fab")
			(hide yes)
			(effects
				(font
					(size 1.016 1.016)
					(thickness 0.1524)
				)
			)
		)
		(property "Device Type" "SOT23CBE2D4H44"
			(at 0.10287 -12.20343 270)
			(unlocked yes)
			(layer "F.Fab")
			(hide yes)
			(effects
				(font
					(size 1.016 1.016)
					(thickness 0.1524)
				)
			)
		)
		(duplicate_pad_numbers_are_jumpers no)
		(fp_line
			(start -1.651 1.778)
			(end 1.651 1.778)
			(stroke
				(width 0.1524)
				(type default)
			)
			(layer "F.SilkS")
		)
		(fp_line
			(start 1.651 1.778)
			(end 1.651 -1.778)
			(stroke
				(width 0.1524)
				(type default)
			)
			(layer "F.SilkS")
		)
		(fp_line
			(start -1.651 -1.778)
			(end -1.651 1.778)
			(stroke
				(width 0.1524)
				(type default)
			)
			(layer "F.SilkS")
		)
		(fp_line
			(start 1.651 -1.778)
			(end -1.651 -1.778)
			(stroke
				(width 0.1524)
				(type default)
			)
			(layer "F.SilkS")
		)
		(fp_poly
			(pts
				(xy -1.778 1.8796) (xy -1.778 -1.8796) (xy 1.778 -1.8796) (xy 1.778 1.8796)
			)
			(stroke
				(width 0)
				(type default)
			)
			(fill no)
			(layer "F.CrtYd")
		)
		(fp_poly
			(pts
				(xy -1.778 1.8796) (xy -1.778 -1.8796) (xy 1.778 -1.8796) (xy 1.778 1.8796)
			)
			(stroke
				(width 0)
				(type default)
			)
			(fill no)
			(layer "F.Fab")
		)
		(pad "B" smd custom
			(at -0.98425 0.9525 270)
			(size 0.1905 0.1905)
			(layers "F.Cu" "F.Mask" "F.Paste")
			(net "MB0_TEMP_C")
			(options
				(clearance outline)
				(anchor circle)
			)
			(primitives
				(gr_poly
					(pts
						(arc
							(start -0.1778 0.5715)
							(mid -0.321484 0.511984)
							(end -0.381 0.3683)
						)
						(arc
							(start -0.381 -0.3683)
							(mid -0.321484 -0.511984)
							(end -0.1778 -0.5715)
						)
						(arc
							(start 0.1778 -0.5715)
							(mid 0.321484 -0.511984)
							(end 0.381 -0.3683)
						)
						(arc
							(start 0.381 0.3683)
							(mid 0.321484 0.511984)
							(end 0.1778 0.5715)
						)
					)
					(width 0)
					(fill yes)
				)
			)
		)
		(pad "C" smd custom
			(at 0 -0.9525 270)
			(size 0.1905 0.1905)
			(layers "F.Cu" "F.Mask" "F.Paste")
			(net "MB0_TEMP_C")
			(options
				(clearance outline)
				(anchor circle)
			)
			(primitives
				(gr_poly
					(pts
						(arc
							(start -0.1778 0.5715)
							(mid -0.321484 0.511984)
							(end -0.381 0.3683)
						)
						(arc
							(start -0.381 -0.3683)
							(mid -0.321484 -0.511984)
							(end -0.1778 -0.5715)
						)
						(arc
							(start 0.1778 -0.5715)
							(mid 0.321484 -0.511984)
							(end 0.381 -0.3683)
						)
						(arc
							(start 0.381 0.3683)
							(mid 0.321484 0.511984)
							(end 0.1778 0.5715)
						)
					)
					(width 0)
					(fill yes)
				)
			)
		)
		(pad "E" smd custom
			(at 0.98425 0.9525 270)
			(size 0.1905 0.1905)
			(layers "F.Cu" "F.Mask" "F.Paste")
			(net "MB0_TEMP_E")
			(options
				(clearance outline)
				(anchor circle)
			)
			(primitives
				(gr_poly
					(pts
						(arc
							(start -0.1778 0.5715)
							(mid -0.321484 0.511984)
							(end -0.381 0.3683)
						)
						(arc
							(start -0.381 -0.3683)
							(mid -0.321484 -0.511984)
							(end -0.1778 -0.5715)
						)
						(arc
							(start 0.1778 -0.5715)
							(mid 0.321484 -0.511984)
							(end 0.381 -0.3683)
						)
						(arc
							(start 0.381 0.3683)
							(mid 0.321484 0.511984)
							(end 0.1778 0.5715)
						)
					)
					(width 0)
					(fill yes)
				)
			)
		)
	)
	(footprint ""
		(layer "F.Cu")
		(at 214.999824 -90.362278)
		(property "Reference" "R826"
			(at 0 0 0)
			(layer "F.SilkS")
			(hide yes)
			(effects
				(font
					(size 1.27 1.27)
				)
			)
		)
		(property "Value" "10KR2F-2-GP"
			(at 0.064008 -3.993896 0)
			(unlocked yes)
			(layer "F.Fab")
			(hide yes)
			(effects
				(font
					(size 1.016 1.016)
					(thickness 0.1524)
				)
			)
		)
		(property "Device Type" "R402H16"
			(at 0.064008 -5.517896 0)
			(unlocked yes)
			(layer "F.Fab")
			(hide yes)
			(effects
				(font
					(size 1.016 1.016)
					(thickness 0.1524)
				)
			)
		)
		(duplicate_pad_numbers_are_jumpers no)
		(fp_line
			(start -0.508 -0.9398)
			(end -0.508 0.9398)
			(stroke
				(width 0.1524)
				(type default)
			)
			(layer "F.SilkS")
		)
		(fp_line
			(start 0.508 -0.9398)
			(end -0.508 -0.9398)
			(stroke
				(width 0.1524)
				(type default)
			)
			(layer "F.SilkS")
		)
		(fp_rect
			(start -0.508 0.9398)
			(end 0.508 -0.9398)
			(stroke
				(width 0)
				(type default)
			)
			(fill no)
			(layer "F.CrtYd")
		)
		(fp_rect
			(start -0.508 0.9398)
			(end 0.508 -0.9398)
			(stroke
				(width 0)
				(type default)
			)
			(fill no)
			(layer "F.Fab")
		)
		(pad "1" smd custom
			(at 0 -0.4445)
			(size 0.1397 0.1397)
			(layers "F.Cu" "F.Mask" "F.Paste")
			(net "IOM_FULL_PGOOD")
			(options
				(clearance outline)
				(anchor circle)
			)
			(primitives
				(gr_poly
					(pts
						(arc
							(start -0.1778 -0.2794)
							(mid -0.249642 -0.249642)
							(end -0.2794 -0.1778)
						)
						(arc
							(start -0.2794 0.1778)
							(mid -0.249642 0.249642)
							(end -0.1778 0.2794)
						)
						(arc
							(start 0.1778 0.2794)
							(mid 0.249642 0.249642)
							(end 0.2794 0.1778)
						)
						(arc
							(start 0.2794 -0.1778)
							(mid 0.249642 -0.249642)
							(end 0.1778 -0.2794)
						)
					)
					(width 0)
					(fill yes)
				)
			)
		)
		(pad "2" smd custom
			(at 0 0.4445)
			(size 0.1397 0.1397)
			(layers "F.Cu" "F.Mask" "F.Paste")
			(net "P3V3_M2_VREG")
			(options
				(clearance outline)
				(anchor circle)
			)
			(primitives
				(gr_poly
					(pts
						(arc
							(start -0.1778 -0.2794)
							(mid -0.249642 -0.249642)
							(end -0.2794 -0.1778)
						)
						(arc
							(start -0.2794 0.1778)
							(mid -0.249642 0.249642)
							(end -0.1778 0.2794)
						)
						(arc
							(start 0.1778 0.2794)
							(mid 0.249642 0.249642)
							(end 0.2794 0.1778)
						)
						(arc
							(start 0.2794 -0.1778)
							(mid 0.249642 -0.249642)
							(end 0.1778 -0.2794)
						)
					)
					(width 0)
					(fill yes)
				)
			)
		)
	)
	(footprint ""
		(layer "F.Cu")
		(at 53.34 -159.2326 90)
		(property "Reference" "C85"
			(at 0 0 90)
			(layer "F.SilkS")
			(hide yes)
			(effects
				(font
					(size 1.27 1.27)
				)
			)
		)
		(property "Value" "SCD1U16V2KX-3GP"
			(at 1.1811 -2.7051 90)
			(unlocked yes)
			(layer "F.Fab")
			(hide yes)
			(effects
				(font
					(size 1.016 1.016)
					(thickness 0.1524)
				)
			)
		)
		(property "Device Type" "C402H22"
			(at 1.1811 -4.2291 90)
			(unlocked yes)
			(layer "F.Fab")
			(hide yes)
			(effects
				(font
					(size 1.016 1.016)
					(thickness 0.1524)
				)
			)
		)
		(duplicate_pad_numbers_are_jumpers no)
		(fp_rect
			(start -0.4318 0.9525)
			(end 0.4318 -0.9525)
			(stroke
				(width 0)
				(type default)
			)
			(fill no)
			(layer "F.CrtYd")
		)
		(fp_rect
			(start -0.4318 0.9525)
			(end 0.4318 -0.9525)
			(stroke
				(width 0)
				(type default)
			)
			(fill no)
			(layer "F.Fab")
		)
		(pad "1" smd custom
			(at 0 -0.4445 90)
			(size 0.1524 0.1524)
			(layers "F.Cu" "F.Mask" "F.Paste")
			(net "GND")
			(options
				(clearance outline)
				(anchor circle)
			)
			(primitives
				(gr_poly
					(pts
						(arc
							(start 0.3048 -0.2032)
							(mid 0.275042 -0.275042)
							(end 0.2032 -0.3048)
						)
						(arc
							(start -0.2032 -0.3048)
							(mid -0.275042 -0.275042)
							(end -0.3048 -0.2032)
						)
						(arc
							(start -0.3048 0.2032)
							(mid -0.275042 0.275042)
							(end -0.2032 0.3048)
						)
						(arc
							(start 0.2032 0.3048)
							(mid 0.275042 0.275042)
							(end 0.3048 0.2032)
						)
					)
					(width 0)
					(fill yes)
				)
			)
		)
		(pad "2" smd custom
			(at 0 0.4445 90)
			(size 0.1524 0.1524)
			(layers "F.Cu" "F.Mask" "F.Paste")
			(net "ADCVREFFN")
			(options
				(clearance outline)
				(anchor circle)
			)
			(primitives
				(gr_poly
					(pts
						(arc
							(start 0.3048 -0.2032)
							(mid 0.275042 -0.275042)
							(end 0.2032 -0.3048)
						)
						(arc
							(start -0.2032 -0.3048)
							(mid -0.275042 -0.275042)
							(end -0.3048 -0.2032)
						)
						(arc
							(start -0.3048 0.2032)
							(mid -0.275042 0.275042)
							(end -0.2032 0.3048)
						)
						(arc
							(start 0.2032 0.3048)
							(mid 0.275042 0.275042)
							(end 0.3048 0.2032)
						)
					)
					(width 0)
					(fill yes)
				)
			)
		)
	)
	(footprint ""
		(layer "F.Cu")
		(at 134.4422 -13.880592 -90)
		(property "Reference" "R442"
			(at 0 0 270)
			(layer "F.SilkS")
			(hide yes)
			(effects
				(font
					(size 1.27 1.27)
				)
			)
		)
		(property "Value" "10R2F-L-GP"
			(at 0.064008 -3.993896 270)
			(unlocked yes)
			(layer "F.Fab")
			(hide yes)
			(effects
				(font
					(size 1.016 1.016)
					(thickness 0.1524)
				)
			)
		)
		(property "Device Type" "R402H14"
			(at 0.064008 -5.517896 270)
			(unlocked yes)
			(layer "F.Fab")
			(hide yes)
			(effects
				(font
					(size 1.016 1.016)
					(thickness 0.1524)
				)
			)
		)
		(duplicate_pad_numbers_are_jumpers no)
		(fp_line
			(start -0.508 -0.9398)
			(end -0.508 0.9398)
			(stroke
				(width 0.1524)
				(type default)
			)
			(layer "F.SilkS")
		)
		(fp_line
			(start 0.508 -0.9398)
			(end -0.508 -0.9398)
			(stroke
				(width 0.1524)
				(type default)
			)
			(layer "F.SilkS")
		)
		(fp_rect
			(start -0.508 0.9398)
			(end 0.508 -0.9398)
			(stroke
				(width 0)
				(type default)
			)
			(fill no)
			(layer "F.CrtYd")
		)
		(fp_rect
			(start -0.508 0.9398)
			(end 0.508 -0.9398)
			(stroke
				(width 0)
				(type default)
			)
			(fill no)
			(layer "F.Fab")
		)
		(pad "1" smd custom
			(at 0 -0.4445 270)
			(size 0.1397 0.1397)
			(layers "F.Cu" "F.Mask" "F.Paste")
			(net "MB0_CM_SENSE_R1_P")
			(options
				(clearance outline)
				(anchor circle)
			)
			(primitives
				(gr_poly
					(pts
						(arc
							(start -0.1778 -0.2794)
							(mid -0.249642 -0.249642)
							(end -0.2794 -0.1778)
						)
						(arc
							(start -0.2794 0.1778)
							(mid -0.249642 0.249642)
							(end -0.1778 0.2794)
						)
						(arc
							(start 0.1778 0.2794)
							(mid 0.249642 0.249642)
							(end 0.2794 0.1778)
						)
						(arc
							(start 0.2794 -0.1778)
							(mid 0.249642 -0.249642)
							(end 0.1778 -0.2794)
						)
					)
					(width 0)
					(fill yes)
				)
			)
		)
		(pad "2" smd custom
			(at 0 0.4445 270)
			(size 0.1397 0.1397)
			(layers "F.Cu" "F.Mask" "F.Paste")
			(net "ADM1278_HS_P")
			(options
				(clearance outline)
				(anchor circle)
			)
			(primitives
				(gr_poly
					(pts
						(arc
							(start -0.1778 -0.2794)
							(mid -0.249642 -0.249642)
							(end -0.2794 -0.1778)
						)
						(arc
							(start -0.2794 0.1778)
							(mid -0.249642 0.249642)
							(end -0.1778 0.2794)
						)
						(arc
							(start 0.1778 0.2794)
							(mid 0.249642 0.249642)
							(end 0.2794 0.1778)
						)
						(arc
							(start 0.2794 -0.1778)
							(mid 0.249642 -0.249642)
							(end 0.1778 -0.2794)
						)
					)
					(width 0)
					(fill yes)
				)
			)
		)
	)
	(footprint ""
		(layer "F.Cu")
		(at 74.718418 -148.365972 180)
		(property "Reference" "C76"
			(at 0 0 180)
			(layer "F.SilkS")
			(hide yes)
			(effects
				(font
					(size 1.27 1.27)
				)
			)
		)
		(property "Value" "SCD01U25V2KX-3GP"
			(at 1.1811 -2.7051 180)
			(unlocked yes)
			(layer "F.Fab")
			(hide yes)
			(effects
				(font
					(size 1.016 1.016)
					(thickness 0.1524)
				)
			)
		)
		(property "Device Type" "C402H22"
			(at 1.1811 -4.2291 180)
			(unlocked yes)
			(layer "F.Fab")
			(hide yes)
			(effects
				(font
					(size 1.016 1.016)
					(thickness 0.1524)
				)
			)
		)
		(duplicate_pad_numbers_are_jumpers no)
		(fp_rect
			(start -0.4318 0.9525)
			(end 0.4318 -0.9525)
			(stroke
				(width 0)
				(type default)
			)
			(fill no)
			(layer "F.CrtYd")
		)
		(fp_rect
			(start -0.4318 0.9525)
			(end 0.4318 -0.9525)
			(stroke
				(width 0)
				(type default)
			)
			(fill no)
			(layer "F.Fab")
		)
		(pad "1" smd custom
			(at 0 -0.4445 180)
			(size 0.1524 0.1524)
			(layers "F.Cu" "F.Mask" "F.Paste")
			(net "P3V3_STBY")
			(options
				(clearance outline)
				(anchor circle)
			)
			(primitives
				(gr_poly
					(pts
						(arc
							(start 0.3048 -0.2032)
							(mid 0.275042 -0.275042)
							(end 0.2032 -0.3048)
						)
						(arc
							(start -0.2032 -0.3048)
							(mid -0.275042 -0.275042)
							(end -0.3048 -0.2032)
						)
						(arc
							(start -0.3048 0.2032)
							(mid -0.275042 0.275042)
							(end -0.2032 0.3048)
						)
						(arc
							(start 0.2032 0.3048)
							(mid 0.275042 0.275042)
							(end 0.3048 0.2032)
						)
					)
					(width 0)
					(fill yes)
				)
			)
		)
		(pad "2" smd custom
			(at 0 0.4445 180)
			(size 0.1524 0.1524)
			(layers "F.Cu" "F.Mask" "F.Paste")
			(net "GND")
			(options
				(clearance outline)
				(anchor circle)
			)
			(primitives
				(gr_poly
					(pts
						(arc
							(start 0.3048 -0.2032)
							(mid 0.275042 -0.275042)
							(end 0.2032 -0.3048)
						)
						(arc
							(start -0.2032 -0.3048)
							(mid -0.275042 -0.275042)
							(end -0.3048 -0.2032)
						)
						(arc
							(start -0.3048 0.2032)
							(mid -0.275042 0.275042)
							(end -0.2032 0.3048)
						)
						(arc
							(start 0.2032 0.3048)
							(mid 0.275042 0.275042)
							(end 0.3048 0.2032)
						)
					)
					(width 0)
					(fill yes)
				)
			)
		)
	)
	(footprint ""
		(layer "F.Cu")
		(at 182.884318 -121.136156 180)
		(property "Reference" "R806"
			(at 0 0 180)
			(layer "F.SilkS")
			(hide yes)
			(effects
				(font
					(size 1.27 1.27)
				)
			)
		)
		(property "Value" "4K7R2F-GP"
			(at 0.064008 -3.993896 180)
			(unlocked yes)
			(layer "F.Fab")
			(hide yes)
			(effects
				(font
					(size 1.016 1.016)
					(thickness 0.1524)
				)
			)
		)
		(property "Device Type" "R402H16"
			(at 0.064008 -5.517896 180)
			(unlocked yes)
			(layer "F.Fab")
			(hide yes)
			(effects
				(font
					(size 1.016 1.016)
					(thickness 0.1524)
				)
			)
		)
		(duplicate_pad_numbers_are_jumpers no)
		(fp_line
			(start 0.508 -0.9398)
			(end -0.508 -0.9398)
			(stroke
				(width 0.1524)
				(type default)
			)
			(layer "F.SilkS")
		)
		(fp_line
			(start -0.508 -0.9398)
			(end -0.508 0.9398)
			(stroke
				(width 0.1524)
				(type default)
			)
			(layer "F.SilkS")
		)
		(fp_rect
			(start -0.508 0.9398)
			(end 0.508 -0.9398)
			(stroke
				(width 0)
				(type default)
			)
			(fill no)
			(layer "F.CrtYd")
		)
		(fp_rect
			(start -0.508 0.9398)
			(end 0.508 -0.9398)
			(stroke
				(width 0)
				(type default)
			)
			(fill no)
			(layer "F.Fab")
		)
		(pad "1" smd custom
			(at 0 -0.4445 180)
			(size 0.1397 0.1397)
			(layers "F.Cu" "F.Mask" "F.Paste")
			(net "P3V3_M2")
			(options
				(clearance outline)
				(anchor circle)
			)
			(primitives
				(gr_poly
					(pts
						(arc
							(start -0.1778 -0.2794)
							(mid -0.249642 -0.249642)
							(end -0.2794 -0.1778)
						)
						(arc
							(start -0.2794 0.1778)
							(mid -0.249642 0.249642)
							(end -0.1778 0.2794)
						)
						(arc
							(start 0.1778 0.2794)
							(mid 0.249642 0.249642)
							(end 0.2794 0.1778)
						)
						(arc
							(start 0.2794 -0.1778)
							(mid 0.249642 -0.249642)
							(end 0.1778 -0.2794)
						)
					)
					(width 0)
					(fill yes)
				)
			)
		)
		(pad "2" smd custom
			(at 0 0.4445 180)
			(size 0.1397 0.1397)
			(layers "F.Cu" "F.Mask" "F.Paste")
			(net "M2_2_CLKREQ#")
			(options
				(clearance outline)
				(anchor circle)
			)
			(primitives
				(gr_poly
					(pts
						(arc
							(start -0.1778 -0.2794)
							(mid -0.249642 -0.249642)
							(end -0.2794 -0.1778)
						)
						(arc
							(start -0.2794 0.1778)
							(mid -0.249642 0.249642)
							(end -0.1778 0.2794)
						)
						(arc
							(start 0.1778 0.2794)
							(mid 0.249642 0.249642)
							(end 0.2794 0.1778)
						)
						(arc
							(start 0.2794 -0.1778)
							(mid 0.249642 -0.249642)
							(end 0.1778 -0.2794)
						)
					)
					(width 0)
					(fill yes)
				)
			)
		)
	)
	(footprint ""
		(layer "F.Cu")
		(at 88.788494 -128.989074 90)
		(property "Reference" "R420"
			(at 0 0 90)
			(layer "F.SilkS")
			(hide yes)
			(effects
				(font
					(size 1.27 1.27)
				)
			)
		)
		(property "Value" "4K7R2F-GP"
			(at 0.064008 -3.993896 90)
			(unlocked yes)
			(layer "F.Fab")
			(hide yes)
			(effects
				(font
					(size 1.016 1.016)
					(thickness 0.1524)
				)
			)
		)
		(property "Device Type" "R402H16"
			(at 0.064008 -5.517896 90)
			(unlocked yes)
			(layer "F.Fab")
			(hide yes)
			(effects
				(font
					(size 1.016 1.016)
					(thickness 0.1524)
				)
			)
		)
		(duplicate_pad_numbers_are_jumpers no)
		(fp_line
			(start 0.508 -0.9398)
			(end -0.508 -0.9398)
			(stroke
				(width 0.1524)
				(type default)
			)
			(layer "F.SilkS")
		)
		(fp_line
			(start -0.508 -0.9398)
			(end -0.508 0.9398)
			(stroke
				(width 0.1524)
				(type default)
			)
			(layer "F.SilkS")
		)
		(fp_rect
			(start -0.508 0.9398)
			(end 0.508 -0.9398)
			(stroke
				(width 0)
				(type default)
			)
			(fill no)
			(layer "F.CrtYd")
		)
		(fp_rect
			(start -0.508 0.9398)
			(end 0.508 -0.9398)
			(stroke
				(width 0)
				(type default)
			)
			(fill no)
			(layer "F.Fab")
		)
		(pad "1" smd custom
			(at 0 -0.4445 90)
			(size 0.1397 0.1397)
			(layers "F.Cu" "F.Mask" "F.Paste")
			(net "P3V3_STBY")
			(options
				(clearance outline)
				(anchor circle)
			)
			(primitives
				(gr_poly
					(pts
						(arc
							(start -0.1778 -0.2794)
							(mid -0.249642 -0.249642)
							(end -0.2794 -0.1778)
						)
						(arc
							(start -0.2794 0.1778)
							(mid -0.249642 0.249642)
							(end -0.1778 0.2794)
						)
						(arc
							(start 0.1778 0.2794)
							(mid 0.249642 0.249642)
							(end 0.2794 0.1778)
						)
						(arc
							(start 0.2794 -0.1778)
							(mid 0.249642 -0.249642)
							(end 0.1778 -0.2794)
						)
					)
					(width 0)
					(fill yes)
				)
			)
		)
		(pad "2" smd custom
			(at 0 0.4445 90)
			(size 0.1397 0.1397)
			(layers "F.Cu" "F.Mask" "F.Paste")
			(net "UART_SEL_MUX")
			(options
				(clearance outline)
				(anchor circle)
			)
			(primitives
				(gr_poly
					(pts
						(arc
							(start -0.1778 -0.2794)
							(mid -0.249642 -0.249642)
							(end -0.2794 -0.1778)
						)
						(arc
							(start -0.2794 0.1778)
							(mid -0.249642 0.249642)
							(end -0.1778 0.2794)
						)
						(arc
							(start 0.1778 0.2794)
							(mid 0.249642 0.249642)
							(end 0.2794 0.1778)
						)
						(arc
							(start 0.2794 -0.1778)
							(mid 0.249642 -0.249642)
							(end 0.1778 -0.2794)
						)
					)
					(width 0)
					(fill yes)
				)
			)
		)
	)
)
